(kicad_pcb
	(version 20260206)
	(generator "pcbnew")
	(generator_version "10.0")
	(general
		(thickness 1.6)
		(legacy_teardrops no)
	)
	(paper "A4")
	(title_block
		(title "Bryce Canyon_F.DPB_16315-1-OCP.brd")
		(comment 1 "Bryce Canyon / footprints 1684-1690 of 2223")
	)
	(layers
		(0 "F.Cu" signal "TOP")
		(4 "In1.Cu" signal "L2GND")
		(6 "In2.Cu" signal "L3")
		(8 "In3.Cu" signal "L4GND")
		(10 "In4.Cu" signal "L5")
		(12 "In5.Cu" signal "L6VCC")
		(14 "In6.Cu" signal "L7VCC")
		(16 "In7.Cu" signal "L8")
		(18 "In8.Cu" signal "L9GND")
		(20 "In9.Cu" signal "L10")
		(22 "In10.Cu" signal "L11GND")
		(2 "B.Cu" signal "BOTTOM")
		(9 "F.Adhes" user "F.Adhesive")
		(11 "B.Adhes" user "B.Adhesive")
		(13 "F.Paste" user "Package Geometry/Pastemask Top")
		(15 "B.Paste" user "Package Geometry/Pastemask Bottom")
		(5 "F.SilkS" user "Ref Des/Silkscreen Top")
		(7 "B.SilkS" user "Ref Des/Silkscreen Bottom")
		(1 "F.Mask" user "Board Geometry/Soldermask Top")
		(3 "B.Mask" user "Board Geometry/Soldermask Bottom")
		(17 "Dwgs.User" user "User.Drawings")
		(19 "Cmts.User" user "User.Comments")
		(21 "Eco1.User" user "User.Eco1")
		(23 "Eco2.User" user "User.Eco2")
		(25 "Edge.Cuts" user "Board Geometry/Outline")
		(27 "Margin" user)
		(31 "F.CrtYd" user "Package Geometry/Place Bound Top")
		(29 "B.CrtYd" user "Package Geometry/Place Bound Bottom")
		(35 "F.Fab" user "Ref Des/Assembly Top")
		(33 "B.Fab" user "Ref Des/Assembly Bottom")
	)
	(footprint ""
		(layer "F.Cu")
		(at 359.0036 -144.6784)
		(property "Reference" "R1072"
			(at 0 0 0)
			(layer "F.SilkS")
			(hide yes)
			(effects
				(font
					(size 1.27 1.27)
				)
			)
		)
		(property "Value" "100R2D-GP"
			(at 0.064008 -3.993896 0)
			(unlocked yes)
			(layer "F.Fab")
			(hide yes)
			(effects
				(font
					(size 1.016 1.016)
					(thickness 0.1524)
				)
			)
		)
		(property "Device Type" "R402H14"
			(at 0.064008 -5.517896 0)
			(unlocked yes)
			(layer "F.Fab")
			(hide yes)
			(effects
				(font
					(size 1.016 1.016)
					(thickness 0.1524)
				)
			)
		)
		(duplicate_pad_numbers_are_jumpers no)
		(fp_line
			(start -0.508 -0.9398)
			(end -0.508 0.9398)
			(stroke
				(width 0.1524)
				(type default)
			)
			(layer "F.SilkS")
		)
		(fp_line
			(start 0.508 -0.9398)
			(end -0.508 -0.9398)
			(stroke
				(width 0.1524)
				(type default)
			)
			(layer "F.SilkS")
		)
		(fp_rect
			(start -0.508 0.9398)
			(end 0.508 -0.9398)
			(stroke
				(width 0)
				(type default)
			)
			(fill no)
			(layer "F.CrtYd")
		)
		(fp_rect
			(start -0.508 0.9398)
			(end 0.508 -0.9398)
			(stroke
				(width 0)
				(type default)
			)
			(fill no)
			(layer "F.Fab")
		)
		(pad "1" smd custom
			(at 0 -0.4445)
			(size 0.1397 0.1397)
			(layers "F.Cu" "F.Mask" "F.Paste")
			(net "GND")
			(options
				(clearance outline)
				(anchor circle)
			)
			(primitives
				(gr_poly
					(pts
						(arc
							(start -0.1778 -0.2794)
							(mid -0.249642 -0.249642)
							(end -0.2794 -0.1778)
						)
						(arc
							(start -0.2794 0.1778)
							(mid -0.249642 0.249642)
							(end -0.1778 0.2794)
						)
						(arc
							(start 0.1778 0.2794)
							(mid 0.249642 0.249642)
							(end 0.2794 0.1778)
						)
						(arc
							(start 0.2794 -0.1778)
							(mid 0.249642 -0.249642)
							(end 0.1778 -0.2794)
						)
					)
					(width 0)
					(fill yes)
				)
			)
		)
		(pad "2" smd custom
			(at 0 0.4445)
			(size 0.1397 0.1397)
			(layers "F.Cu" "F.Mask" "F.Paste")
			(net "MB1_TEMP_E")
			(options
				(clearance outline)
				(anchor circle)
			)
			(primitives
				(gr_poly
					(pts
						(arc
							(start -0.1778 -0.2794)
							(mid -0.249642 -0.249642)
							(end -0.2794 -0.1778)
						)
						(arc
							(start -0.2794 0.1778)
							(mid -0.249642 0.249642)
							(end -0.1778 0.2794)
						)
						(arc
							(start 0.1778 0.2794)
							(mid 0.249642 0.249642)
							(end 0.2794 0.1778)
						)
						(arc
							(start 0.2794 -0.1778)
							(mid 0.249642 -0.249642)
							(end 0.1778 -0.2794)
						)
					)
					(width 0)
					(fill yes)
				)
			)
		)
	)
	(footprint ""
		(layer "F.Cu")
		(at 392.91895 -74.335894 180)
		(property "Reference" "C463"
			(at 0 0 180)
			(layer "F.SilkS")
			(hide yes)
			(effects
				(font
					(size 1.27 1.27)
				)
			)
		)
		(property "Value" "SC1U25V3KX-GP"
			(at 0 -2.8194 180)
			(unlocked yes)
			(layer "F.Fab")
			(hide yes)
			(effects
				(font
					(size 1.016 1.016)
					(thickness 0.1524)
				)
			)
		)
		(property "Device Type" "C603H36"
			(at 0 -4.3434 180)
			(unlocked yes)
			(layer "F.Fab")
			(hide yes)
			(effects
				(font
					(size 1.016 1.016)
					(thickness 0.1524)
				)
			)
		)
		(duplicate_pad_numbers_are_jumpers no)
		(fp_line
			(start 0.508 0)
			(end -0.508 0)
			(stroke
				(width 0.2032)
				(type default)
			)
			(layer "F.SilkS")
		)
		(fp_rect
			(start -0.5842 1.3335)
			(end 0.5842 -1.3335)
			(stroke
				(width 0)
				(type default)
			)
			(fill no)
			(layer "F.CrtYd")
		)
		(fp_rect
			(start -0.5842 1.3335)
			(end 0.5842 -1.3335)
			(stroke
				(width 0)
				(type default)
			)
			(fill no)
			(layer "F.Fab")
		)
		(pad "1" smd custom
			(at 0 -0.762 180)
			(size 0.2159 0.2159)
			(layers "F.Cu" "F.Mask" "F.Paste")
			(net "P12V_HDD32")
			(options
				(clearance outline)
				(anchor circle)
			)
			(primitives
				(gr_poly
					(pts
						(arc
							(start -0.3302 -0.4318)
							(mid -0.402042 -0.402042)
							(end -0.4318 -0.3302)
						)
						(arc
							(start -0.4318 0.3302)
							(mid -0.402042 0.402042)
							(end -0.3302 0.4318)
						)
						(arc
							(start 0.3302 0.4318)
							(mid 0.402042 0.402042)
							(end 0.4318 0.3302)
						)
						(arc
							(start 0.4318 -0.3302)
							(mid 0.402042 -0.402042)
							(end 0.3302 -0.4318)
						)
					)
					(width 0)
					(fill yes)
				)
			)
		)
		(pad "2" smd custom
			(at 0 0.762 180)
			(size 0.2159 0.2159)
			(layers "F.Cu" "F.Mask" "F.Paste")
			(net "GND")
			(options
				(clearance outline)
				(anchor circle)
			)
			(primitives
				(gr_poly
					(pts
						(arc
							(start -0.3302 -0.4318)
							(mid -0.402042 -0.402042)
							(end -0.4318 -0.3302)
						)
						(arc
							(start -0.4318 0.3302)
							(mid -0.402042 0.402042)
							(end -0.3302 0.4318)
						)
						(arc
							(start 0.3302 0.4318)
							(mid 0.402042 0.402042)
							(end 0.4318 0.3302)
						)
						(arc
							(start 0.4318 -0.3302)
							(mid 0.402042 -0.402042)
							(end 0.3302 -0.4318)
						)
					)
					(width 0)
					(fill yes)
				)
			)
		)
	)
	(footprint ""
		(layer "F.Cu")
		(at 477.2406 -48.067976 180)
		(property "Reference" "R935"
			(at 0 0 180)
			(layer "F.SilkS")
			(hide yes)
			(effects
				(font
					(size 1.27 1.27)
				)
			)
		)
		(property "Value" "10KR2F-2-GP"
			(at 0.064008 -3.993896 180)
			(unlocked yes)
			(layer "F.Fab")
			(hide yes)
			(effects
				(font
					(size 1.016 1.016)
					(thickness 0.1524)
				)
			)
		)
		(property "Device Type" "R402H16"
			(at 0.064008 -5.517896 180)
			(unlocked yes)
			(layer "F.Fab")
			(hide yes)
			(effects
				(font
					(size 1.016 1.016)
					(thickness 0.1524)
				)
			)
		)
		(duplicate_pad_numbers_are_jumpers no)
		(fp_line
			(start 0.508 -0.9398)
			(end -0.508 -0.9398)
			(stroke
				(width 0.1524)
				(type default)
			)
			(layer "F.SilkS")
		)
		(fp_line
			(start -0.508 -0.9398)
			(end -0.508 0.9398)
			(stroke
				(width 0.1524)
				(type default)
			)
			(layer "F.SilkS")
		)
		(fp_rect
			(start -0.508 0.9398)
			(end 0.508 -0.9398)
			(stroke
				(width 0)
				(type default)
			)
			(fill no)
			(layer "F.CrtYd")
		)
		(fp_rect
			(start -0.508 0.9398)
			(end 0.508 -0.9398)
			(stroke
				(width 0)
				(type default)
			)
			(fill no)
			(layer "F.Fab")
		)
		(pad "1" smd custom
			(at 0 -0.4445 180)
			(size 0.1397 0.1397)
			(layers "F.Cu" "F.Mask" "F.Paste")
			(net "P3V3_STBY_A")
			(options
				(clearance outline)
				(anchor circle)
			)
			(primitives
				(gr_poly
					(pts
						(arc
							(start -0.1778 -0.2794)
							(mid -0.249642 -0.249642)
							(end -0.2794 -0.1778)
						)
						(arc
							(start -0.2794 0.1778)
							(mid -0.249642 0.249642)
							(end -0.1778 0.2794)
						)
						(arc
							(start 0.1778 0.2794)
							(mid 0.249642 0.249642)
							(end 0.2794 0.1778)
						)
						(arc
							(start 0.2794 -0.1778)
							(mid 0.249642 -0.249642)
							(end 0.1778 -0.2794)
						)
					)
					(width 0)
					(fill yes)
				)
			)
		)
		(pad "2" smd custom
			(at 0 0.4445 180)
			(size 0.1397 0.1397)
			(layers "F.Cu" "F.Mask" "F.Paste")
			(net "HDD_PRSNT_35")
			(options
				(clearance outline)
				(anchor circle)
			)
			(primitives
				(gr_poly
					(pts
						(arc
							(start -0.1778 -0.2794)
							(mid -0.249642 -0.249642)
							(end -0.2794 -0.1778)
						)
						(arc
							(start -0.2794 0.1778)
							(mid -0.249642 0.249642)
							(end -0.1778 0.2794)
						)
						(arc
							(start 0.1778 0.2794)
							(mid 0.249642 0.249642)
							(end 0.2794 0.1778)
						)
						(arc
							(start 0.2794 -0.1778)
							(mid 0.249642 -0.249642)
							(end 0.1778 -0.2794)
						)
					)
					(width 0)
					(fill yes)
				)
			)
		)
	)
	(footprint ""
		(layer "F.Cu")
		(at 141.042898 -168.507918 -90)
		(property "Reference" "R513"
			(at 0 0 270)
			(layer "F.SilkS")
			(hide yes)
			(effects
				(font
					(size 1.27 1.27)
				)
			)
		)
		(property "Value" "300KR2F-GP"
			(at 0.064008 -3.993896 270)
			(unlocked yes)
			(layer "F.Fab")
			(hide yes)
			(effects
				(font
					(size 1.016 1.016)
					(thickness 0.1524)
				)
			)
		)
		(property "Device Type" "R402H16"
			(at 0.064008 -5.517896 270)
			(unlocked yes)
			(layer "F.Fab")
			(hide yes)
			(effects
				(font
					(size 1.016 1.016)
					(thickness 0.1524)
				)
			)
		)
		(duplicate_pad_numbers_are_jumpers no)
		(fp_line
			(start -0.508 -0.9398)
			(end -0.508 0.9398)
			(stroke
				(width 0.1524)
				(type default)
			)
			(layer "F.SilkS")
		)
		(fp_line
			(start 0.508 -0.9398)
			(end -0.508 -0.9398)
			(stroke
				(width 0.1524)
				(type default)
			)
			(layer "F.SilkS")
		)
		(fp_rect
			(start -0.508 0.9398)
			(end 0.508 -0.9398)
			(stroke
				(width 0)
				(type default)
			)
			(fill no)
			(layer "F.CrtYd")
		)
		(fp_rect
			(start -0.508 0.9398)
			(end 0.508 -0.9398)
			(stroke
				(width 0)
				(type default)
			)
			(fill no)
			(layer "F.Fab")
		)
		(pad "1" smd custom
			(at 0 -0.4445 270)
			(size 0.1397 0.1397)
			(layers "F.Cu" "F.Mask" "F.Paste")
			(net "SW_HDD_N16")
			(options
				(clearance outline)
				(anchor circle)
			)
			(primitives
				(gr_poly
					(pts
						(arc
							(start -0.1778 -0.2794)
							(mid -0.249642 -0.249642)
							(end -0.2794 -0.1778)
						)
						(arc
							(start -0.2794 0.1778)
							(mid -0.249642 0.249642)
							(end -0.1778 0.2794)
						)
						(arc
							(start 0.1778 0.2794)
							(mid 0.249642 0.249642)
							(end 0.2794 0.1778)
						)
						(arc
							(start 0.2794 -0.1778)
							(mid 0.249642 -0.249642)
							(end 0.1778 -0.2794)
						)
					)
					(width 0)
					(fill yes)
				)
			)
		)
		(pad "2" smd custom
			(at 0 0.4445 270)
			(size 0.1397 0.1397)
			(layers "F.Cu" "F.Mask" "F.Paste")
			(net "P12V_A")
			(options
				(clearance outline)
				(anchor circle)
			)
			(primitives
				(gr_poly
					(pts
						(arc
							(start -0.1778 -0.2794)
							(mid -0.249642 -0.249642)
							(end -0.2794 -0.1778)
						)
						(arc
							(start -0.2794 0.1778)
							(mid -0.249642 0.249642)
							(end -0.1778 0.2794)
						)
						(arc
							(start 0.1778 0.2794)
							(mid 0.249642 0.249642)
							(end 0.2794 0.1778)
						)
						(arc
							(start 0.2794 -0.1778)
							(mid 0.249642 -0.249642)
							(end 0.1778 -0.2794)
						)
					)
					(width 0)
					(fill yes)
				)
			)
		)
	)
	(footprint ""
		(layer "F.Cu")
		(at 222.6437 -91.2114 -90)
		(property "Reference" "R200"
			(at 0 0 270)
			(layer "F.SilkS")
			(hide yes)
			(effects
				(font
					(size 1.27 1.27)
				)
			)
		)
		(property "Value" "4K7R2F-GP"
			(at 0.064008 -3.993896 270)
			(unlocked yes)
			(layer "F.Fab")
			(hide yes)
			(effects
				(font
					(size 1.016 1.016)
					(thickness 0.1524)
				)
			)
		)
		(property "Device Type" "R402H16"
			(at 0.064008 -5.517896 270)
			(unlocked yes)
			(layer "F.Fab")
			(hide yes)
			(effects
				(font
					(size 1.016 1.016)
					(thickness 0.1524)
				)
			)
		)
		(duplicate_pad_numbers_are_jumpers no)
		(fp_line
			(start -0.508 -0.9398)
			(end -0.508 0.9398)
			(stroke
				(width 0.1524)
				(type default)
			)
			(layer "F.SilkS")
		)
		(fp_line
			(start 0.508 -0.9398)
			(end -0.508 -0.9398)
			(stroke
				(width 0.1524)
				(type default)
			)
			(layer "F.SilkS")
		)
		(fp_rect
			(start -0.508 0.9398)
			(end 0.508 -0.9398)
			(stroke
				(width 0)
				(type default)
			)
			(fill no)
			(layer "F.CrtYd")
		)
		(fp_rect
			(start -0.508 0.9398)
			(end 0.508 -0.9398)
			(stroke
				(width 0)
				(type default)
			)
			(fill no)
			(layer "F.Fab")
		)
		(pad "1" smd custom
			(at 0 -0.4445 270)
			(size 0.1397 0.1397)
			(layers "F.Cu" "F.Mask" "F.Paste")
			(net "COMP_A_POWER_FAIL_N")
			(options
				(clearance outline)
				(anchor circle)
			)
			(primitives
				(gr_poly
					(pts
						(arc
							(start -0.1778 -0.2794)
							(mid -0.249642 -0.249642)
							(end -0.2794 -0.1778)
						)
						(arc
							(start -0.2794 0.1778)
							(mid -0.249642 0.249642)
							(end -0.1778 0.2794)
						)
						(arc
							(start 0.1778 0.2794)
							(mid 0.249642 0.249642)
							(end 0.2794 0.1778)
						)
						(arc
							(start 0.2794 -0.1778)
							(mid 0.249642 -0.249642)
							(end 0.1778 -0.2794)
						)
					)
					(width 0)
					(fill yes)
				)
			)
		)
		(pad "2" smd custom
			(at 0 0.4445 270)
			(size 0.1397 0.1397)
			(layers "F.Cu" "F.Mask" "F.Paste")
			(net "P3V3_STBY_A")
			(options
				(clearance outline)
				(anchor circle)
			)
			(primitives
				(gr_poly
					(pts
						(arc
							(start -0.1778 -0.2794)
							(mid -0.249642 -0.249642)
							(end -0.2794 -0.1778)
						)
						(arc
							(start -0.2794 0.1778)
							(mid -0.249642 0.249642)
							(end -0.1778 0.2794)
						)
						(arc
							(start 0.1778 0.2794)
							(mid 0.249642 0.249642)
							(end 0.2794 0.1778)
						)
						(arc
							(start 0.2794 -0.1778)
							(mid 0.249642 -0.249642)
							(end 0.1778 -0.2794)
						)
					)
					(width 0)
					(fill yes)
				)
			)
		)
	)
	(footprint ""
		(layer "F.Cu")
		(at 50.456846 -179.683918 90)
		(property "Reference" "R430"
			(at 0 0 90)
			(layer "F.SilkS")
			(hide yes)
			(effects
				(font
					(size 1.27 1.27)
				)
			)
		)
		(property "Value" "2R6F-GP"
			(at -0.0508 -4.8514 90)
			(unlocked yes)
			(layer "F.Fab")
			(hide yes)
			(effects
				(font
					(size 1.016 1.016)
					(thickness 0.1524)
				)
			)
		)
		(property "Device Type" "R1206H26"
			(at 0 -6.3754 90)
			(unlocked yes)
			(layer "F.Fab")
			(hide yes)
			(effects
				(font
					(size 1.016 1.016)
					(thickness 0.1524)
				)
			)
		)
		(duplicate_pad_numbers_are_jumpers no)
		(fp_line
			(start 1.016 -2.2352)
			(end 1.016 2.2352)
			(stroke
				(width 0.1524)
				(type default)
			)
			(layer "F.SilkS")
		)
		(fp_line
			(start -1.016 -2.2352)
			(end 1.016 -2.2352)
			(stroke
				(width 0.1524)
				(type default)
			)
			(layer "F.SilkS")
		)
		(fp_line
			(start 1.016 2.2352)
			(end -1.016 2.2352)
			(stroke
				(width 0.1524)
				(type default)
			)
			(layer "F.SilkS")
		)
		(fp_line
			(start -1.016 2.2352)
			(end -1.016 -2.2352)
			(stroke
				(width 0.1524)
				(type default)
			)
			(layer "F.SilkS")
		)
		(fp_rect
			(start -1.0922 2.3114)
			(end 1.0922 -2.3114)
			(stroke
				(width 0)
				(type default)
			)
			(fill no)
			(layer "F.CrtYd")
		)
		(fp_poly
			(pts
				(xy -1.0922 -2.3114) (xy 1.0922 -2.3114) (xy 1.0922 2.3114) (xy -1.0922 2.3114)
			)
			(stroke
				(width 0)
				(type default)
			)
			(fill no)
			(layer "F.Fab")
		)
		(pad "1" smd rect
			(at 0 -1.397 90)
			(size 1.651 1.27)
			(layers "F.Cu" "F.Mask" "F.Paste")
			(net "P12V_HDD13")
		)
		(pad "2" smd rect
			(at 0 1.397 90)
			(size 1.651 1.27)
			(layers "F.Cu" "F.Mask" "F.Paste")
			(net "12V_PRE_13")
		)
	)
	(footprint ""
		(layer "F.Cu")
		(at 222.885 -365.125)
		(property "Reference" "R176"
			(at 0 0 0)
			(layer "F.SilkS")
			(hide yes)
			(effects
				(font
					(size 1.27 1.27)
				)
			)
		)
		(property "Value" "4K7R2F-GP"
			(at 0.064008 -3.993896 0)
			(unlocked yes)
			(layer "F.Fab")
			(hide yes)
			(effects
				(font
					(size 1.016 1.016)
					(thickness 0.1524)
				)
			)
		)
		(property "Device Type" "R402H16"
			(at 0.064008 -5.517896 0)
			(unlocked yes)
			(layer "F.Fab")
			(hide yes)
			(effects
				(font
					(size 1.016 1.016)
					(thickness 0.1524)
				)
			)
		)
		(duplicate_pad_numbers_are_jumpers no)
		(fp_line
			(start -0.508 -0.9398)
			(end -0.508 0.9398)
			(stroke
				(width 0.1524)
				(type default)
			)
			(layer "F.SilkS")
		)
		(fp_line
			(start 0.508 -0.9398)
			(end -0.508 -0.9398)
			(stroke
				(width 0.1524)
				(type default)
			)
			(layer "F.SilkS")
		)
		(fp_rect
			(start -0.508 0.9398)
			(end 0.508 -0.9398)
			(stroke
				(width 0)
				(type default)
			)
			(fill no)
			(layer "F.CrtYd")
		)
		(fp_rect
			(start -0.508 0.9398)
			(end 0.508 -0.9398)
			(stroke
				(width 0)
				(type default)
			)
			(fill no)
			(layer "F.Fab")
		)
		(pad "1" smd custom
			(at 0 -0.4445)
			(size 0.1397 0.1397)
			(layers "F.Cu" "F.Mask" "F.Paste")
			(net "IO_EXP3_HDD_FAULT_A1")
			(options
				(clearance outline)
				(anchor circle)
			)
			(primitives
				(gr_poly
					(pts
						(arc
							(start -0.1778 -0.2794)
							(mid -0.249642 -0.249642)
							(end -0.2794 -0.1778)
						)
						(arc
							(start -0.2794 0.1778)
							(mid -0.249642 0.249642)
							(end -0.1778 0.2794)
						)
						(arc
							(start 0.1778 0.2794)
							(mid 0.249642 0.249642)
							(end 0.2794 0.1778)
						)
						(arc
							(start 0.2794 -0.1778)
							(mid 0.249642 -0.249642)
							(end 0.1778 -0.2794)
						)
					)
					(width 0)
					(fill yes)
				)
			)
		)
		(pad "2" smd custom
			(at 0 0.4445)
			(size 0.1397 0.1397)
			(layers "F.Cu" "F.Mask" "F.Paste")
			(net "GND")
			(options
				(clearance outline)
				(anchor circle)
			)
			(primitives
				(gr_poly
					(pts
						(arc
							(start -0.1778 -0.2794)
							(mid -0.249642 -0.249642)
							(end -0.2794 -0.1778)
						)
						(arc
							(start -0.2794 0.1778)
							(mid -0.249642 0.249642)
							(end -0.1778 0.2794)
						)
						(arc
							(start 0.1778 0.2794)
							(mid 0.249642 0.249642)
							(end 0.2794 0.1778)
						)
						(arc
							(start 0.2794 -0.1778)
							(mid 0.249642 -0.249642)
							(end 0.1778 -0.2794)
						)
					)
					(width 0)
					(fill yes)
				)
			)
		)
	)
)
